# SCM (Grand Teton) — schematic netlist excerpt (pin names and nets, part order shuffled) for the footprints in the layout excerpt that follows; sources: Cadence DE-HDL packaged netlist, KiCad conversion of 12092022_DA0F0TMDCD0_F0T_Management_Board_D_brd_V3_OCP.brd

PC252  Q_CAP  10UF 25V 10% X6S  pkg C0805  page 55 : A = SW_P1V2_AUX_FLT ; B = GND
R682  Q_RES  33.2 1% EMPTY  pkg 0402LF  page 13 : A = SPI_BMC_IO3_R ; B = QSPI_2_PLD_IO3

(kicad_pcb
	(version 20260206)
	(generator "pcbnew")
	(generator_version "10.0")
	(general
		(thickness 1.6)
		(legacy_teardrops no)
	)
	(paper "A4")
	(title_block
		(title "12092022_DA0F0TMDCD0_F0T_Management_Board_D_brd_V3_OCP.brd")
		(comment 1 "Grand Teton / footprints 567-568 of 1440")
	)
	(layers
		(0 "F.Cu" signal "TOP")
		(4 "In1.Cu" signal "GND")
		(6 "In2.Cu" signal "IN1")
		(8 "In3.Cu" signal "GND1")
		(10 "In4.Cu" signal "IN2")
		(12 "In5.Cu" signal "VCC")
		(14 "In6.Cu" signal "VCC1")
		(16 "In7.Cu" signal "IN3")
		(18 "In8.Cu" signal "GND2")
		(20 "In9.Cu" signal "IN4")
		(22 "In10.Cu" signal "GND3")
		(2 "B.Cu" signal "BOTTOM")
		(9 "F.Adhes" user "F.Adhesive")
		(11 "B.Adhes" user "B.Adhesive")
		(13 "F.Paste" user "Package Geometry/Pastemask Top")
		(15 "B.Paste" user "Package Geometry/Pastemask Bottom")
		(5 "F.SilkS" user "Ref Des/Silkscreen Top")
		(7 "B.SilkS" user "Ref Des/Silkscreen Bottom")
		(1 "F.Mask" user "Board Geometry/Soldermask Top")
		(3 "B.Mask" user "Board Geometry/Soldermask Bottom")
		(17 "Dwgs.User" user "User.Drawings")
		(19 "Cmts.User" user "User.Comments")
		(21 "Eco1.User" user "User.Eco1")
		(23 "Eco2.User" user "User.Eco2")
		(25 "Edge.Cuts" user "Board Geometry/Outline")
		(27 "Margin" user)
		(31 "F.CrtYd" user "Package Geometry/Place Bound Top")
		(29 "B.CrtYd" user "Package Geometry/Place Bound Bottom")
		(35 "F.Fab" user "Ref Des/Assembly Top")
		(33 "B.Fab" user "Ref Des/Assembly Bottom")
	)
	(footprint ""
		(layer "F.Cu")
		(at 53.213 -69.723 90)
		(property "Reference" "R682"
			(at 0 0 90)
			(layer "F.SilkS")
			(hide yes)
			(effects
				(font
					(size 1.27 1.27)
				)
			)
		)
		(property "Value" ""
			(at 0 0 90)
			(layer "F.Fab")
			(effects
				(font
					(size 1.27 1.27)
				)
			)
		)
		(duplicate_pad_numbers_are_jumpers no)
		(fp_line
			(start 0.7874 -0.4064)
			(end 0.7874 0.4064)
			(stroke
				(width 0.1524)
				(type default)
			)
			(layer "F.SilkS")
		)
		(fp_line
			(start -0.7874 -0.4064)
			(end 0.7874 -0.4064)
			(stroke
				(width 0.1524)
				(type default)
			)
			(layer "F.SilkS")
		)
		(fp_line
			(start 0.7874 0.4064)
			(end -0.7874 0.4064)
			(stroke
				(width 0.1524)
				(type default)
			)
			(layer "F.SilkS")
		)
		(fp_line
			(start -0.7874 0.4064)
			(end -0.7874 -0.4064)
			(stroke
				(width 0.1524)
				(type default)
			)
			(layer "F.SilkS")
		)
		(fp_line
			(start -0.12065 -0.305054)
			(end -0.12065 -0.2794)
			(stroke
				(width 0.1)
				(type default)
			)
			(layer "F.Fab")
		)
		(fp_line
			(start -0.67945 -0.305054)
			(end -0.12065 -0.305054)
			(stroke
				(width 0.1)
				(type default)
			)
			(layer "F.Fab")
		)
		(fp_line
			(start 0.67945 -0.3048)
			(end 0.67945 0.3048)
			(stroke
				(width 0.1)
				(type default)
			)
			(layer "F.Fab")
		)
		(fp_line
			(start 0.12065 -0.3048)
			(end 0.67945 -0.3048)
			(stroke
				(width 0.1)
				(type default)
			)
			(layer "F.Fab")
		)
		(fp_line
			(start 0.12065 -0.2794)
			(end 0.12065 -0.3048)
			(stroke
				(width 0.1)
				(type default)
			)
			(layer "F.Fab")
		)
		(fp_line
			(start -0.12065 -0.2794)
			(end 0.12065 -0.2794)
			(stroke
				(width 0.1)
				(type default)
			)
			(layer "F.Fab")
		)
		(fp_line
			(start 0.120396 0.2794)
			(end -0.12065 0.2794)
			(stroke
				(width 0.1)
				(type default)
			)
			(layer "F.Fab")
		)
		(fp_line
			(start -0.12065 0.2794)
			(end -0.12065 0.3048)
			(stroke
				(width 0.1)
				(type default)
			)
			(layer "F.Fab")
		)
		(fp_line
			(start 0.67945 0.3048)
			(end 0.120396 0.3048)
			(stroke
				(width 0.1)
				(type default)
			)
			(layer "F.Fab")
		)
		(fp_line
			(start 0.120396 0.3048)
			(end 0.120396 0.2794)
			(stroke
				(width 0.1)
				(type default)
			)
			(layer "F.Fab")
		)
		(fp_line
			(start -0.12065 0.3048)
			(end -0.67945 0.3048)
			(stroke
				(width 0.1)
				(type default)
			)
			(layer "F.Fab")
		)
		(fp_line
			(start -0.67945 0.3048)
			(end -0.67945 -0.305054)
			(stroke
				(width 0.1)
				(type default)
			)
			(layer "F.Fab")
		)
		(pad "1" smd circle
			(at -0.40005 0 90)
			(size 0 0)
			(layers "F.Cu" "F.Mask" "F.Paste")
			(net "SPI_BMC_IO3_R")
		)
		(pad "2" smd circle
			(at 0.40005 0 90)
			(size 0 0)
			(layers "F.Cu" "F.Mask" "F.Paste")
			(net "QSPI_2_PLD_IO3")
		)
	)
	(footprint ""
		(layer "F.Cu")
		(at 81.755996 -76.258928 180)
		(property "Reference" "PC252"
			(at 0 0 180)
			(layer "F.SilkS")
			(hide yes)
			(effects
				(font
					(size 1.27 1.27)
				)
			)
		)
		(property "Value" ""
			(at 0 0 180)
			(layer "F.Fab")
			(effects
				(font
					(size 1.27 1.27)
				)
			)
		)
		(duplicate_pad_numbers_are_jumpers no)
		(fp_line
			(start 1.651 0.8382)
			(end -1.651 0.8382)
			(stroke
				(width 0.1524)
				(type default)
			)
			(layer "F.SilkS")
		)
		(fp_line
			(start 1.651 -0.8382)
			(end 1.651 0.8382)
			(stroke
				(width 0.1524)
				(type default)
			)
			(layer "F.SilkS")
		)
		(fp_line
			(start 0 0.8382)
			(end 0 -0.8382)
			(stroke
				(width 0.1524)
				(type default)
			)
			(layer "F.SilkS")
		)
		(fp_line
			(start -1.651 0.8382)
			(end -1.651 -0.8382)
			(stroke
				(width 0.1524)
				(type default)
			)
			(layer "F.SilkS")
		)
		(fp_line
			(start -1.651 -0.8382)
			(end 1.651 -0.8382)
			(stroke
				(width 0.1524)
				(type default)
			)
			(layer "F.SilkS")
		)
		(fp_line
			(start 1.55956 0.7366)
			(end 1.55956 -0.7366)
			(stroke
				(width 0.1)
				(type default)
			)
			(layer "F.Fab")
		)
		(fp_line
			(start 1.55956 -0.7366)
			(end 1.524 -0.7366)
			(stroke
				(width 0.1)
				(type default)
			)
			(layer "F.Fab")
		)
		(fp_line
			(start 1.524 0.7366)
			(end 1.55956 0.7366)
			(stroke
				(width 0.1)
				(type default)
			)
			(layer "F.Fab")
		)
		(fp_line
			(start 1.524 -0.7366)
			(end -1.524 -0.7366)
			(stroke
				(width 0.1)
				(type default)
			)
			(layer "F.Fab")
		)
		(fp_line
			(start -1.524 0.7366)
			(end 1.524 0.7366)
			(stroke
				(width 0.1)
				(type default)
			)
			(layer "F.Fab")
		)
		(fp_line
			(start -1.524 -0.7366)
			(end -1.55956 -0.7366)
			(stroke
				(width 0.1)
				(type default)
			)
			(layer "F.Fab")
		)
		(fp_line
			(start -1.55956 0.7366)
			(end -1.524 0.7366)
			(stroke
				(width 0.1)
				(type default)
			)
			(layer "F.Fab")
		)
		(fp_line
			(start -1.55956 -0.7366)
			(end -1.55956 0.7366)
			(stroke
				(width 0.1)
				(type default)
			)
			(layer "F.Fab")
		)
		(pad "1" smd rect
			(at -0.94996 0)
			(size 1.1176 1.3716)
			(layers "F.Cu" "F.Mask" "F.Paste")
			(net "SW_P1V2_AUX_FLT")
		)
		(pad "2" smd rect
			(at 0.94996 0)
			(size 1.1176 1.3716)
			(layers "F.Cu" "F.Mask" "F.Paste")
			(net "GND")
		)
	)
)
